(kicad_pcb
	(version 20260206)
	(generator "pcbnew")
	(generator_version "10.0")
	(general
		(thickness 1.6)
		(legacy_teardrops no)
	)
	(paper "A4")
	(title_block
		(title "04192023_DAF0TMB3IC0_F0TG_MB_C_brd_V02_OCP.brd")
		(comment 1 "Grand Teton / footprints 309-314 of 8354")
	)
	(layers
		(0 "F.Cu" signal "TOP")
		(4 "In1.Cu" signal "GND")
		(6 "In2.Cu" signal "IN1")
		(8 "In3.Cu" signal "GND1")
		(10 "In4.Cu" signal "IN2")
		(12 "In5.Cu" signal "GND2")
		(14 "In6.Cu" signal "IN3")
		(16 "In7.Cu" signal "GND3")
		(18 "In8.Cu" signal "VCC")
		(20 "In9.Cu" signal "VCC1")
		(22 "In10.Cu" signal "GND4")
		(24 "In11.Cu" signal "IN4")
		(26 "In12.Cu" signal "GND5")
		(28 "In13.Cu" signal "IN5")
		(30 "In14.Cu" signal "GND6")
		(32 "In15.Cu" signal "IN6")
		(34 "In16.Cu" signal "GND7")
		(2 "B.Cu" signal "BOTTOM")
		(9 "F.Adhes" user "F.Adhesive")
		(11 "B.Adhes" user "B.Adhesive")
		(13 "F.Paste" user "Package Geometry/Pastemask Top")
		(15 "B.Paste" user "Package Geometry/Pastemask Bottom")
		(5 "F.SilkS" user "Ref Des/Silkscreen Top")
		(7 "B.SilkS" user "Ref Des/Silkscreen Bottom")
		(1 "F.Mask" user "Board Geometry/Soldermask Top")
		(3 "B.Mask" user "Board Geometry/Soldermask Bottom")
		(17 "Dwgs.User" user "User.Drawings")
		(19 "Cmts.User" user "User.Comments")
		(21 "Eco1.User" user "User.Eco1")
		(23 "Eco2.User" user "User.Eco2")
		(25 "Edge.Cuts" user "Board Geometry/Outline")
		(27 "Margin" user)
		(31 "F.CrtYd" user "Package Geometry/Place Bound Top")
		(29 "B.CrtYd" user "Package Geometry/Place Bound Bottom")
		(35 "F.Fab" user "Ref Des/Assembly Top")
		(33 "B.Fab" user "Ref Des/Assembly Bottom")
	)
	(footprint ""
		(layer "F.Cu")
		(at 297.486324 -122.349514 180)
		(property "Reference" "R316"
			(at 0 0 180)
			(layer "F.SilkS")
			(hide yes)
			(effects
				(font
					(size 1.27 1.27)
				)
			)
		)
		(property "Value" ""
			(at 0 0 180)
			(layer "F.Fab")
			(effects
				(font
					(size 1.27 1.27)
				)
			)
		)
		(duplicate_pad_numbers_are_jumpers no)
		(fp_line
			(start 0.7874 0.4064)
			(end -0.7874 0.4064)
			(stroke
				(width 0.1524)
				(type default)
			)
			(layer "F.SilkS")
		)
		(fp_line
			(start 0.7874 -0.4064)
			(end 0.7874 0.4064)
			(stroke
				(width 0.1524)
				(type default)
			)
			(layer "F.SilkS")
		)
		(fp_line
			(start -0.7874 0.4064)
			(end -0.7874 -0.4064)
			(stroke
				(width 0.1524)
				(type default)
			)
			(layer "F.SilkS")
		)
		(fp_line
			(start -0.7874 -0.4064)
			(end 0.7874 -0.4064)
			(stroke
				(width 0.1524)
				(type default)
			)
			(layer "F.SilkS")
		)
		(fp_line
			(start 0.67945 0.3048)
			(end 0.120396 0.3048)
			(stroke
				(width 0.1)
				(type default)
			)
			(layer "F.Fab")
		)
		(fp_line
			(start 0.67945 -0.3048)
			(end 0.67945 0.3048)
			(stroke
				(width 0.1)
				(type default)
			)
			(layer "F.Fab")
		)
		(fp_line
			(start 0.12065 -0.2794)
			(end 0.12065 -0.3048)
			(stroke
				(width 0.1)
				(type default)
			)
			(layer "F.Fab")
		)
		(fp_line
			(start 0.12065 -0.3048)
			(end 0.67945 -0.3048)
			(stroke
				(width 0.1)
				(type default)
			)
			(layer "F.Fab")
		)
		(fp_line
			(start 0.120396 0.3048)
			(end 0.120396 0.2794)
			(stroke
				(width 0.1)
				(type default)
			)
			(layer "F.Fab")
		)
		(fp_line
			(start 0.120396 0.2794)
			(end -0.12065 0.2794)
			(stroke
				(width 0.1)
				(type default)
			)
			(layer "F.Fab")
		)
		(fp_line
			(start -0.12065 0.3048)
			(end -0.67945 0.3048)
			(stroke
				(width 0.1)
				(type default)
			)
			(layer "F.Fab")
		)
		(fp_line
			(start -0.12065 0.2794)
			(end -0.12065 0.3048)
			(stroke
				(width 0.1)
				(type default)
			)
			(layer "F.Fab")
		)
		(fp_line
			(start -0.12065 -0.2794)
			(end 0.12065 -0.2794)
			(stroke
				(width 0.1)
				(type default)
			)
			(layer "F.Fab")
		)
		(fp_line
			(start -0.12065 -0.305054)
			(end -0.12065 -0.2794)
			(stroke
				(width 0.1)
				(type default)
			)
			(layer "F.Fab")
		)
		(fp_line
			(start -0.67945 0.3048)
			(end -0.67945 -0.305054)
			(stroke
				(width 0.1)
				(type default)
			)
			(layer "F.Fab")
		)
		(fp_line
			(start -0.67945 -0.305054)
			(end -0.12065 -0.305054)
			(stroke
				(width 0.1)
				(type default)
			)
			(layer "F.Fab")
		)
		(pad "1" smd circle
			(at -0.40005 0 180)
			(size 0 0)
			(layers "F.Cu" "F.Mask" "F.Paste")
			(net "P3V3_AUX")
		)
		(pad "2" smd circle
			(at 0.40005 0 180)
			(size 0 0)
			(layers "F.Cu" "F.Mask" "F.Paste")
			(net "PCA9548_PCIE3_ADDR2")
		)
	)
	(footprint ""
		(layer "F.Cu")
		(at 115.70589 -259.845302)
		(property "Reference" "C2267"
			(at 0 0 0)
			(layer "F.SilkS")
			(hide yes)
			(effects
				(font
					(size 1.27 1.27)
				)
			)
		)
		(property "Value" ""
			(at 0 0 0)
			(layer "F.Fab")
			(effects
				(font
					(size 1.27 1.27)
				)
			)
		)
		(duplicate_pad_numbers_are_jumpers no)
		(fp_line
			(start -0.7874 -0.4064)
			(end 0.7874 -0.4064)
			(stroke
				(width 0.1524)
				(type default)
			)
			(layer "F.SilkS")
		)
		(fp_line
			(start -0.7874 0.4064)
			(end -0.7874 -0.4064)
			(stroke
				(width 0.1524)
				(type default)
			)
			(layer "F.SilkS")
		)
		(fp_line
			(start 0.7874 -0.4064)
			(end 0.7874 0.4064)
			(stroke
				(width 0.1524)
				(type default)
			)
			(layer "F.SilkS")
		)
		(fp_line
			(start 0.7874 0.4064)
			(end -0.7874 0.4064)
			(stroke
				(width 0.1524)
				(type default)
			)
			(layer "F.SilkS")
		)
		(fp_line
			(start -0.67945 -0.305054)
			(end -0.12065 -0.305054)
			(stroke
				(width 0.1)
				(type default)
			)
			(layer "F.Fab")
		)
		(fp_line
			(start -0.67945 0.3048)
			(end -0.67945 -0.305054)
			(stroke
				(width 0.1)
				(type default)
			)
			(layer "F.Fab")
		)
		(fp_line
			(start -0.12065 -0.305054)
			(end -0.12065 -0.2794)
			(stroke
				(width 0.1)
				(type default)
			)
			(layer "F.Fab")
		)
		(fp_line
			(start -0.12065 -0.2794)
			(end 0.12065 -0.2794)
			(stroke
				(width 0.1)
				(type default)
			)
			(layer "F.Fab")
		)
		(fp_line
			(start -0.12065 0.2794)
			(end -0.12065 0.3048)
			(stroke
				(width 0.1)
				(type default)
			)
			(layer "F.Fab")
		)
		(fp_line
			(start -0.12065 0.3048)
			(end -0.67945 0.3048)
			(stroke
				(width 0.1)
				(type default)
			)
			(layer "F.Fab")
		)
		(fp_line
			(start 0.120396 0.2794)
			(end -0.12065 0.2794)
			(stroke
				(width 0.1)
				(type default)
			)
			(layer "F.Fab")
		)
		(fp_line
			(start 0.120396 0.3048)
			(end 0.120396 0.2794)
			(stroke
				(width 0.1)
				(type default)
			)
			(layer "F.Fab")
		)
		(fp_line
			(start 0.12065 -0.3048)
			(end 0.67945 -0.3048)
			(stroke
				(width 0.1)
				(type default)
			)
			(layer "F.Fab")
		)
		(fp_line
			(start 0.12065 -0.2794)
			(end 0.12065 -0.3048)
			(stroke
				(width 0.1)
				(type default)
			)
			(layer "F.Fab")
		)
		(fp_line
			(start 0.67945 -0.3048)
			(end 0.67945 0.3048)
			(stroke
				(width 0.1)
				(type default)
			)
			(layer "F.Fab")
		)
		(fp_line
			(start 0.67945 0.3048)
			(end 0.120396 0.3048)
			(stroke
				(width 0.1)
				(type default)
			)
			(layer "F.Fab")
		)
		(pad "1" smd circle
			(at -0.40005 0)
			(size 0 0)
			(layers "F.Cu" "F.Mask" "F.Paste")
			(net "PVDD11_S3_P1")
		)
		(pad "2" smd circle
			(at 0.40005 0)
			(size 0 0)
			(layers "F.Cu" "F.Mask" "F.Paste")
			(net "GND")
		)
	)
	(footprint ""
		(layer "F.Cu")
		(at 155.444444 -375.49963 -90)
		(property "Reference" "C758"
			(at 0 0 270)
			(layer "F.SilkS")
			(hide yes)
			(effects
				(font
					(size 1.27 1.27)
				)
			)
		)
		(property "Value" ""
			(at 0 0 270)
			(layer "F.Fab")
			(effects
				(font
					(size 1.27 1.27)
				)
			)
		)
		(duplicate_pad_numbers_are_jumpers no)
		(fp_line
			(start -0.299974 0.150114)
			(end -0.299974 -0.150114)
			(stroke
				(width 0.1)
				(type default)
			)
			(layer "F.Fab")
		)
		(fp_line
			(start 0.299974 0.150114)
			(end -0.299974 0.150114)
			(stroke
				(width 0.1)
				(type default)
			)
			(layer "F.Fab")
		)
		(fp_line
			(start -0.299974 -0.150114)
			(end 0.299974 -0.150114)
			(stroke
				(width 0.1)
				(type default)
			)
			(layer "F.Fab")
		)
		(fp_line
			(start 0.299974 -0.150114)
			(end 0.299974 0.150114)
			(stroke
				(width 0.1)
				(type default)
			)
			(layer "F.Fab")
		)
		(pad "1" smd rect
			(at -0.2667 0 270)
			(size 0.3048 0.381)
			(layers "F.Cu" "F.Mask" "F.Paste")
			(net "P5E_CPU1_P2_TX_C_DN<7>")
		)
		(pad "2" smd rect
			(at 0.2667 0 270)
			(size 0.3048 0.381)
			(layers "F.Cu" "F.Mask" "F.Paste")
			(net "P5E_CPU1_P2_TX_DN<7>")
		)
	)
	(footprint ""
		(layer "F.Cu")
		(at 288.325306 -346.714572 -90)
		(property "Reference" "PC144_IOP0_2"
			(at 0 0 270)
			(layer "F.SilkS")
			(hide yes)
			(effects
				(font
					(size 1.27 1.27)
				)
			)
		)
		(property "Value" ""
			(at 0 0 270)
			(layer "F.Fab")
			(effects
				(font
					(size 1.27 1.27)
				)
			)
		)
		(duplicate_pad_numbers_are_jumpers no)
		(fp_line
			(start -0.7874 0.4064)
			(end -0.7874 -0.4064)
			(stroke
				(width 0.1524)
				(type default)
			)
			(layer "F.SilkS")
		)
		(fp_line
			(start 0.7874 0.4064)
			(end -0.7874 0.4064)
			(stroke
				(width 0.1524)
				(type default)
			)
			(layer "F.SilkS")
		)
		(fp_line
			(start -0.7874 -0.4064)
			(end 0.7874 -0.4064)
			(stroke
				(width 0.1524)
				(type default)
			)
			(layer "F.SilkS")
		)
		(fp_line
			(start 0.7874 -0.4064)
			(end 0.7874 0.4064)
			(stroke
				(width 0.1524)
				(type default)
			)
			(layer "F.SilkS")
		)
		(fp_line
			(start -0.67945 0.3048)
			(end -0.67945 -0.305054)
			(stroke
				(width 0.1)
				(type default)
			)
			(layer "F.Fab")
		)
		(fp_line
			(start -0.12065 0.3048)
			(end -0.67945 0.3048)
			(stroke
				(width 0.1)
				(type default)
			)
			(layer "F.Fab")
		)
		(fp_line
			(start 0.120396 0.3048)
			(end 0.120396 0.2794)
			(stroke
				(width 0.1)
				(type default)
			)
			(layer "F.Fab")
		)
		(fp_line
			(start 0.67945 0.3048)
			(end 0.120396 0.3048)
			(stroke
				(width 0.1)
				(type default)
			)
			(layer "F.Fab")
		)
		(fp_line
			(start -0.12065 0.2794)
			(end -0.12065 0.3048)
			(stroke
				(width 0.1)
				(type default)
			)
			(layer "F.Fab")
		)
		(fp_line
			(start 0.120396 0.2794)
			(end -0.12065 0.2794)
			(stroke
				(width 0.1)
				(type default)
			)
			(layer "F.Fab")
		)
		(fp_line
			(start -0.12065 -0.2794)
			(end 0.12065 -0.2794)
			(stroke
				(width 0.1)
				(type default)
			)
			(layer "F.Fab")
		)
		(fp_line
			(start 0.12065 -0.2794)
			(end 0.12065 -0.3048)
			(stroke
				(width 0.1)
				(type default)
			)
			(layer "F.Fab")
		)
		(fp_line
			(start 0.12065 -0.3048)
			(end 0.67945 -0.3048)
			(stroke
				(width 0.1)
				(type default)
			)
			(layer "F.Fab")
		)
		(fp_line
			(start 0.67945 -0.3048)
			(end 0.67945 0.3048)
			(stroke
				(width 0.1)
				(type default)
			)
			(layer "F.Fab")
		)
		(fp_line
			(start -0.67945 -0.305054)
			(end -0.12065 -0.305054)
			(stroke
				(width 0.1)
				(type default)
			)
			(layer "F.Fab")
		)
		(fp_line
			(start -0.12065 -0.305054)
			(end -0.12065 -0.2794)
			(stroke
				(width 0.1)
				(type default)
			)
			(layer "F.Fab")
		)
		(pad "1" smd circle
			(at -0.40005 0 270)
			(size 0 0)
			(layers "F.Cu" "F.Mask" "F.Paste")
			(net "PVDDCR_CPU1_P0_PVCC")
		)
		(pad "2" smd circle
			(at 0.40005 0 270)
			(size 0 0)
			(layers "F.Cu" "F.Mask" "F.Paste")
			(net "GND")
		)
	)
	(footprint ""
		(layer "F.Cu")
		(at 313.8297 -409.104592)
		(property "Reference" "C7032"
			(at -5.4864 3.171952 0)
			(unlocked yes)
			(layer "F.SilkS")
			(effects
				(font
					(size 0.7874 0.5842)
					(thickness 0.1524)
				)
				(justify left)
			)
		)
		(property "Value" ""
			(at 0 0 0)
			(layer "F.Fab")
			(effects
				(font
					(size 1.27 1.27)
				)
			)
		)
		(duplicate_pad_numbers_are_jumpers no)
		(fp_line
			(start -4.84378 -2.150618)
			(end -4.842256 2.163064)
			(stroke
				(width 0.1524)
				(type default)
			)
			(layer "F.SilkS")
		)
		(fp_line
			(start -4.84378 -2.150618)
			(end -4.53898 -2.150618)
			(stroke
				(width 0.1524)
				(type default)
			)
			(layer "F.SilkS")
		)
		(fp_line
			(start -4.83108 2.150364)
			(end -4.447794 2.149348)
			(stroke
				(width 0.1524)
				(type default)
			)
			(layer "F.SilkS")
		)
		(fp_line
			(start -4.69138 -2.150618)
			(end -4.692396 2.161032)
			(stroke
				(width 0.1524)
				(type default)
			)
			(layer "F.SilkS")
		)
		(fp_line
			(start -4.53898 -2.150618)
			(end -4.539742 2.152142)
			(stroke
				(width 0.1524)
				(type default)
			)
			(layer "F.SilkS")
		)
		(fp_line
			(start -4.53898 -2.15011)
			(end 4.53898 -2.15011)
			(stroke
				(width 0.1524)
				(type default)
			)
			(layer "F.SilkS")
		)
		(fp_line
			(start -4.53898 2.15011)
			(end -4.53898 -2.15011)
			(stroke
				(width 0.1524)
				(type default)
			)
			(layer "F.SilkS")
		)
		(fp_line
			(start 4.53898 -2.15011)
			(end 4.53898 2.15011)
			(stroke
				(width 0.1524)
				(type default)
			)
			(layer "F.SilkS")
		)
		(fp_line
			(start 4.53898 2.15011)
			(end -4.53898 2.15011)
			(stroke
				(width 0.1524)
				(type default)
			)
			(layer "F.SilkS")
		)
		(fp_line
			(start -3.64998 -2.15011)
			(end 3.64998 -2.15011)
			(stroke
				(width 0.1)
				(type default)
			)
			(layer "F.Fab")
		)
		(fp_line
			(start -3.64998 2.15011)
			(end -3.64998 -2.15011)
			(stroke
				(width 0.1)
				(type default)
			)
			(layer "F.Fab")
		)
		(fp_line
			(start 3.64998 -2.15011)
			(end 3.64998 2.15011)
			(stroke
				(width 0.1)
				(type default)
			)
			(layer "F.Fab")
		)
		(fp_line
			(start 3.64998 2.15011)
			(end -3.64998 2.15011)
			(stroke
				(width 0.1)
				(type default)
			)
			(layer "F.Fab")
		)
		(fp_text user "+"
			(at -6.161532 0.996442 0)
			(unlocked yes)
			(layer "F.SilkS")
			(effects
				(font
					(size 1.905 1.4224)
					(thickness 0.1524)
				)
				(justify left)
			)
		)
		(fp_text user "-"
			(at 6.662166 -2.306828 180)
			(unlocked yes)
			(layer "F.SilkS")
			(effects
				(font
					(size 1.905 1.4224)
					(thickness 0.1524)
				)
				(justify left)
			)
		)
		(fp_text user "+"
			(at -6.214872 -0.337058 0)
			(unlocked yes)
			(layer "F.Fab")
			(effects
				(font
					(size 1.905 1.4224)
					(thickness 0.1524)
				)
				(justify left)
			)
		)
		(fp_text user "-"
			(at 4.313174 -0.094488 0)
			(unlocked yes)
			(layer "F.Fab")
			(effects
				(font
					(size 1.905 1.4224)
					(thickness 0.1524)
				)
				(justify left)
			)
		)
		(pad "1" smd rect
			(at -3.199892 0)
			(size 2.413 2.8194)
			(layers "F.Cu" "F.Mask" "F.Paste")
			(net "P0V9_CPU0_RT_2D")
		)
		(pad "2" smd rect
			(at 3.199892 0)
			(size 2.413 2.8194)
			(layers "F.Cu" "F.Mask" "F.Paste")
			(net "GND")
		)
	)
	(footprint ""
		(layer "F.Cu")
		(at 120.396 -432.054)
		(property "Reference" "R3449"
			(at 0 0 0)
			(layer "F.SilkS")
			(hide yes)
			(effects
				(font
					(size 1.27 1.27)
				)
			)
		)
		(property "Value" ""
			(at 0 0 0)
			(layer "F.Fab")
			(effects
				(font
					(size 1.27 1.27)
				)
			)
		)
		(duplicate_pad_numbers_are_jumpers no)
		(fp_line
			(start -0.7874 -0.4064)
			(end 0.7874 -0.4064)
			(stroke
				(width 0.1524)
				(type default)
			)
			(layer "F.SilkS")
		)
		(fp_line
			(start -0.7874 0.4064)
			(end -0.7874 -0.4064)
			(stroke
				(width 0.1524)
				(type default)
			)
			(layer "F.SilkS")
		)
		(fp_line
			(start 0.7874 -0.4064)
			(end 0.7874 0.4064)
			(stroke
				(width 0.1524)
				(type default)
			)
			(layer "F.SilkS")
		)
		(fp_line
			(start 0.7874 0.4064)
			(end -0.7874 0.4064)
			(stroke
				(width 0.1524)
				(type default)
			)
			(layer "F.SilkS")
		)
		(fp_line
			(start -0.67945 -0.305054)
			(end -0.12065 -0.305054)
			(stroke
				(width 0.1)
				(type default)
			)
			(layer "F.Fab")
		)
		(fp_line
			(start -0.67945 0.3048)
			(end -0.67945 -0.305054)
			(stroke
				(width 0.1)
				(type default)
			)
			(layer "F.Fab")
		)
		(fp_line
			(start -0.12065 -0.305054)
			(end -0.12065 -0.2794)
			(stroke
				(width 0.1)
				(type default)
			)
			(layer "F.Fab")
		)
		(fp_line
			(start -0.12065 -0.2794)
			(end 0.12065 -0.2794)
			(stroke
				(width 0.1)
				(type default)
			)
			(layer "F.Fab")
		)
		(fp_line
			(start -0.12065 0.2794)
			(end -0.12065 0.3048)
			(stroke
				(width 0.1)
				(type default)
			)
			(layer "F.Fab")
		)
		(fp_line
			(start -0.12065 0.3048)
			(end -0.67945 0.3048)
			(stroke
				(width 0.1)
				(type default)
			)
			(layer "F.Fab")
		)
		(fp_line
			(start 0.120396 0.2794)
			(end -0.12065 0.2794)
			(stroke
				(width 0.1)
				(type default)
			)
			(layer "F.Fab")
		)
		(fp_line
			(start 0.120396 0.3048)
			(end 0.120396 0.2794)
			(stroke
				(width 0.1)
				(type default)
			)
			(layer "F.Fab")
		)
		(fp_line
			(start 0.12065 -0.3048)
			(end 0.67945 -0.3048)
			(stroke
				(width 0.1)
				(type default)
			)
			(layer "F.Fab")
		)
		(fp_line
			(start 0.12065 -0.2794)
			(end 0.12065 -0.3048)
			(stroke
				(width 0.1)
				(type default)
			)
			(layer "F.Fab")
		)
		(fp_line
			(start 0.67945 -0.3048)
			(end 0.67945 0.3048)
			(stroke
				(width 0.1)
				(type default)
			)
			(layer "F.Fab")
		)
		(fp_line
			(start 0.67945 0.3048)
			(end 0.120396 0.3048)
			(stroke
				(width 0.1)
				(type default)
			)
			(layer "F.Fab")
		)
		(pad "1" smd circle
			(at -0.40005 0)
			(size 0 0)
			(layers "F.Cu" "F.Mask" "F.Paste")
			(net "GPU_FPGA_BOOT_EN")
		)
		(pad "2" smd circle
			(at 0.40005 0)
			(size 0 0)
			(layers "F.Cu" "F.Mask" "F.Paste")
			(net "GND")
		)
	)
)
